(kicad_pcb
	(version 20260206)
	(generator "pcbnew")
	(generator_version "10.0")
	(general
		(thickness 1.6)
		(legacy_teardrops no)
	)
	(paper "A4")
	(title_block
		(title "pdpb — Lightning_PDPB_BRD.brd")
		(comment 1 "Lightning (Wiwynn / Facebook NVMe JBOF) / footprints 223-229 of 1140")
	)
	(layers
		(0 "F.Cu" signal "TOP")
		(4 "In1.Cu" signal "L2GND")
		(6 "In2.Cu" signal "L3")
		(8 "In3.Cu" signal "L4VCC")
		(10 "In4.Cu" signal "L5VCC")
		(12 "In5.Cu" signal "L6")
		(14 "In6.Cu" signal "L7GND")
		(2 "B.Cu" signal "BOTTOM")
		(9 "F.Adhes" user "F.Adhesive")
		(11 "B.Adhes" user "B.Adhesive")
		(13 "F.Paste" user "Package Geometry/Pastemask Top")
		(15 "B.Paste" user "Package Geometry/Pastemask Bottom")
		(5 "F.SilkS" user "Ref Des/Silkscreen Top")
		(7 "B.SilkS" user "Ref Des/Silkscreen Bottom")
		(1 "F.Mask" user "Board Geometry/Soldermask Top")
		(3 "B.Mask" user "Board Geometry/Soldermask Bottom")
		(17 "Dwgs.User" user "User.Drawings")
		(19 "Cmts.User" user "User.Comments")
		(21 "Eco1.User" user "User.Eco1")
		(23 "Eco2.User" user "User.Eco2")
		(25 "Edge.Cuts" user "Board Geometry/Outline")
		(27 "Margin" user)
		(31 "F.CrtYd" user "Package Geometry/Place Bound Top")
		(29 "B.CrtYd" user "Package Geometry/Place Bound Bottom")
		(35 "F.Fab" user "Ref Des/Assembly Top")
		(33 "B.Fab" user "Ref Des/Assembly Bottom")
	)
	(footprint ""
		(layer "F.Cu")
		(at 206.67345 -198.95185 90)
		(property "Reference" "R9799"
			(at 0 0 90)
			(layer "F.SilkS")
			(hide yes)
			(effects
				(font
					(size 1.27 1.27)
				)
			)
		)
		(property "Value" "1KR2J-1-GP"
			(at 0.064008 -3.993896 90)
			(unlocked yes)
			(layer "F.Fab")
			(hide yes)
			(effects
				(font
					(size 1.016 1.016)
					(thickness 0.1524)
				)
			)
		)
		(property "Device Type" "R402H16"
			(at 0.064008 -5.517896 90)
			(unlocked yes)
			(layer "F.Fab")
			(hide yes)
			(effects
				(font
					(size 1.016 1.016)
					(thickness 0.1524)
				)
			)
		)
		(duplicate_pad_numbers_are_jumpers no)
		(fp_line
			(start 0.508 -0.9398)
			(end -0.508 -0.9398)
			(stroke
				(width 0.1524)
				(type default)
			)
			(layer "F.SilkS")
		)
		(fp_line
			(start -0.508 -0.9398)
			(end -0.508 0.9398)
			(stroke
				(width 0.1524)
				(type default)
			)
			(layer "F.SilkS")
		)
		(fp_rect
			(start -0.508 0.9398)
			(end 0.508 -0.9398)
			(stroke
				(width 0)
				(type default)
			)
			(fill no)
			(layer "F.CrtYd")
		)
		(fp_rect
			(start -0.508 0.9398)
			(end 0.508 -0.9398)
			(stroke
				(width 0)
				(type default)
			)
			(fill no)
			(layer "F.Fab")
		)
		(pad "1" smd custom
			(at 0 -0.4445 90)
			(size 0.1397 0.1397)
			(layers "F.Cu" "F.Mask" "F.Paste")
			(net "SSD3_PWREN")
			(options
				(clearance outline)
				(anchor circle)
			)
			(primitives
				(gr_poly
					(pts
						(arc
							(start -0.1778 -0.2794)
							(mid -0.249642 -0.249642)
							(end -0.2794 -0.1778)
						)
						(arc
							(start -0.2794 0.1778)
							(mid -0.249642 0.249642)
							(end -0.1778 0.2794)
						)
						(arc
							(start 0.1778 0.2794)
							(mid 0.249642 0.249642)
							(end 0.2794 0.1778)
						)
						(arc
							(start 0.2794 -0.1778)
							(mid 0.249642 -0.249642)
							(end 0.1778 -0.2794)
						)
					)
					(width 0)
					(fill yes)
				)
			)
		)
		(pad "2" smd custom
			(at 0 0.4445 90)
			(size 0.1397 0.1397)
			(layers "F.Cu" "F.Mask" "F.Paste")
			(net "SSD3_PWREN_R")
			(options
				(clearance outline)
				(anchor circle)
			)
			(primitives
				(gr_poly
					(pts
						(arc
							(start -0.1778 -0.2794)
							(mid -0.249642 -0.249642)
							(end -0.2794 -0.1778)
						)
						(arc
							(start -0.2794 0.1778)
							(mid -0.249642 0.249642)
							(end -0.1778 0.2794)
						)
						(arc
							(start 0.1778 0.2794)
							(mid 0.249642 0.249642)
							(end 0.2794 0.1778)
						)
						(arc
							(start 0.2794 -0.1778)
							(mid 0.249642 -0.249642)
							(end 0.1778 -0.2794)
						)
					)
					(width 0)
					(fill yes)
				)
			)
		)
	)
	(footprint ""
		(layer "F.Cu")
		(at 234.061 -453.771 -90)
		(property "Reference" "R111"
			(at 0 0 270)
			(layer "F.SilkS")
			(hide yes)
			(effects
				(font
					(size 1.27 1.27)
				)
			)
		)
		(property "Value" "330R2F-GP"
			(at 0.064008 -3.993896 270)
			(unlocked yes)
			(layer "F.Fab")
			(hide yes)
			(effects
				(font
					(size 1.016 1.016)
					(thickness 0.1524)
				)
			)
		)
		(property "Device Type" "R402H16"
			(at 0.064008 -5.517896 270)
			(unlocked yes)
			(layer "F.Fab")
			(hide yes)
			(effects
				(font
					(size 1.016 1.016)
					(thickness 0.1524)
				)
			)
		)
		(duplicate_pad_numbers_are_jumpers no)
		(fp_line
			(start -0.508 -0.9398)
			(end -0.508 0.9398)
			(stroke
				(width 0.1524)
				(type default)
			)
			(layer "F.SilkS")
		)
		(fp_line
			(start 0.508 -0.9398)
			(end -0.508 -0.9398)
			(stroke
				(width 0.1524)
				(type default)
			)
			(layer "F.SilkS")
		)
		(fp_rect
			(start -0.508 0.9398)
			(end 0.508 -0.9398)
			(stroke
				(width 0)
				(type default)
			)
			(fill no)
			(layer "F.CrtYd")
		)
		(fp_rect
			(start -0.508 0.9398)
			(end 0.508 -0.9398)
			(stroke
				(width 0)
				(type default)
			)
			(fill no)
			(layer "F.Fab")
		)
		(pad "1" smd custom
			(at 0 -0.4445 270)
			(size 0.1397 0.1397)
			(layers "F.Cu" "F.Mask" "F.Paste")
			(net "P3V3")
			(options
				(clearance outline)
				(anchor circle)
			)
			(primitives
				(gr_poly
					(pts
						(arc
							(start -0.1778 -0.2794)
							(mid -0.249642 -0.249642)
							(end -0.2794 -0.1778)
						)
						(arc
							(start -0.2794 0.1778)
							(mid -0.249642 0.249642)
							(end -0.1778 0.2794)
						)
						(arc
							(start 0.1778 0.2794)
							(mid 0.249642 0.249642)
							(end 0.2794 0.1778)
						)
						(arc
							(start 0.2794 -0.1778)
							(mid 0.249642 -0.249642)
							(end 0.1778 -0.2794)
						)
					)
					(width 0)
					(fill yes)
				)
			)
		)
		(pad "2" smd custom
			(at 0 0.4445 270)
			(size 0.1397 0.1397)
			(layers "F.Cu" "F.Mask" "F.Paste")
			(net "DRV_ATTN_0")
			(options
				(clearance outline)
				(anchor circle)
			)
			(primitives
				(gr_poly
					(pts
						(arc
							(start -0.1778 -0.2794)
							(mid -0.249642 -0.249642)
							(end -0.2794 -0.1778)
						)
						(arc
							(start -0.2794 0.1778)
							(mid -0.249642 0.249642)
							(end -0.1778 0.2794)
						)
						(arc
							(start 0.1778 0.2794)
							(mid 0.249642 0.249642)
							(end 0.2794 0.1778)
						)
						(arc
							(start 0.2794 -0.1778)
							(mid 0.249642 -0.249642)
							(end 0.1778 -0.2794)
						)
					)
					(width 0)
					(fill yes)
				)
			)
		)
	)
	(footprint ""
		(layer "F.Cu")
		(at 32.131 -494.157 180)
		(property "Reference" "SR1102"
			(at 0 0 180)
			(layer "F.SilkS")
			(hide yes)
			(effects
				(font
					(size 1.27 1.27)
				)
			)
		)
		(property "Value" "4K7R2F-GP"
			(at 0.064008 -3.993896 180)
			(unlocked yes)
			(layer "F.Fab")
			(hide yes)
			(effects
				(font
					(size 1.016 1.016)
					(thickness 0.1524)
				)
			)
		)
		(property "Device Type" "R402H16"
			(at 0.064008 -5.517896 180)
			(unlocked yes)
			(layer "F.Fab")
			(hide yes)
			(effects
				(font
					(size 1.016 1.016)
					(thickness 0.1524)
				)
			)
		)
		(duplicate_pad_numbers_are_jumpers no)
		(fp_line
			(start 0.508 -0.9398)
			(end -0.508 -0.9398)
			(stroke
				(width 0.1524)
				(type default)
			)
			(layer "F.SilkS")
		)
		(fp_line
			(start -0.508 -0.9398)
			(end -0.508 0.9398)
			(stroke
				(width 0.1524)
				(type default)
			)
			(layer "F.SilkS")
		)
		(fp_rect
			(start -0.508 0.9398)
			(end 0.508 -0.9398)
			(stroke
				(width 0)
				(type default)
			)
			(fill no)
			(layer "F.CrtYd")
		)
		(fp_rect
			(start -0.508 0.9398)
			(end 0.508 -0.9398)
			(stroke
				(width 0)
				(type default)
			)
			(fill no)
			(layer "F.Fab")
		)
		(pad "1" smd custom
			(at 0 -0.4445 180)
			(size 0.1397 0.1397)
			(layers "F.Cu" "F.Mask" "F.Paste")
			(net "DUALPORTEN#5")
			(options
				(clearance outline)
				(anchor circle)
			)
			(primitives
				(gr_poly
					(pts
						(arc
							(start -0.1778 -0.2794)
							(mid -0.249642 -0.249642)
							(end -0.2794 -0.1778)
						)
						(arc
							(start -0.2794 0.1778)
							(mid -0.249642 0.249642)
							(end -0.1778 0.2794)
						)
						(arc
							(start 0.1778 0.2794)
							(mid 0.249642 0.249642)
							(end 0.2794 0.1778)
						)
						(arc
							(start 0.2794 -0.1778)
							(mid 0.249642 -0.249642)
							(end 0.1778 -0.2794)
						)
					)
					(width 0)
					(fill yes)
				)
			)
		)
		(pad "2" smd custom
			(at 0 0.4445 180)
			(size 0.1397 0.1397)
			(layers "F.Cu" "F.Mask" "F.Paste")
			(net "GND")
			(options
				(clearance outline)
				(anchor circle)
			)
			(primitives
				(gr_poly
					(pts
						(arc
							(start -0.1778 -0.2794)
							(mid -0.249642 -0.249642)
							(end -0.2794 -0.1778)
						)
						(arc
							(start -0.2794 0.1778)
							(mid -0.249642 0.249642)
							(end -0.1778 0.2794)
						)
						(arc
							(start 0.1778 0.2794)
							(mid 0.249642 0.249642)
							(end 0.2794 0.1778)
						)
						(arc
							(start 0.2794 -0.1778)
							(mid 0.249642 -0.249642)
							(end 0.1778 -0.2794)
						)
					)
					(width 0)
					(fill yes)
				)
			)
		)
	)
	(footprint ""
		(layer "F.Cu")
		(at 222.0214 -291.973)
		(property "Reference" "PC1193"
			(at 0 0 0)
			(layer "F.SilkS")
			(hide yes)
			(effects
				(font
					(size 1.27 1.27)
				)
			)
		)
		(property "Value" "SCD01U50V2KX-1GP"
			(at 1.1811 -2.7051 0)
			(unlocked yes)
			(layer "F.Fab")
			(hide yes)
			(effects
				(font
					(size 1.016 1.016)
					(thickness 0.1524)
				)
			)
		)
		(property "Device Type" "C402H22"
			(at 1.1811 -4.2291 0)
			(unlocked yes)
			(layer "F.Fab")
			(hide yes)
			(effects
				(font
					(size 1.016 1.016)
					(thickness 0.1524)
				)
			)
		)
		(duplicate_pad_numbers_are_jumpers no)
		(fp_rect
			(start -0.4318 0.9525)
			(end 0.4318 -0.9525)
			(stroke
				(width 0)
				(type default)
			)
			(fill no)
			(layer "F.CrtYd")
		)
		(fp_rect
			(start -0.4318 0.9525)
			(end 0.4318 -0.9525)
			(stroke
				(width 0)
				(type default)
			)
			(fill no)
			(layer "F.Fab")
		)
		(pad "1" smd custom
			(at 0 -0.4445)
			(size 0.1524 0.1524)
			(layers "F.Cu" "F.Mask" "F.Paste")
			(net "P12V_SSD2")
			(options
				(clearance outline)
				(anchor circle)
			)
			(primitives
				(gr_poly
					(pts
						(arc
							(start 0.3048 -0.2032)
							(mid 0.275042 -0.275042)
							(end 0.2032 -0.3048)
						)
						(arc
							(start -0.2032 -0.3048)
							(mid -0.275042 -0.275042)
							(end -0.3048 -0.2032)
						)
						(arc
							(start -0.3048 0.2032)
							(mid -0.275042 0.275042)
							(end -0.2032 0.3048)
						)
						(arc
							(start 0.2032 0.3048)
							(mid 0.275042 0.275042)
							(end 0.3048 0.2032)
						)
					)
					(width 0)
					(fill yes)
				)
			)
		)
		(pad "2" smd custom
			(at 0 0.4445)
			(size 0.1524 0.1524)
			(layers "F.Cu" "F.Mask" "F.Paste")
			(net "GND")
			(options
				(clearance outline)
				(anchor circle)
			)
			(primitives
				(gr_poly
					(pts
						(arc
							(start 0.3048 -0.2032)
							(mid 0.275042 -0.275042)
							(end 0.2032 -0.3048)
						)
						(arc
							(start -0.2032 -0.3048)
							(mid -0.275042 -0.275042)
							(end -0.3048 -0.2032)
						)
						(arc
							(start -0.3048 0.2032)
							(mid -0.275042 0.275042)
							(end -0.2032 0.3048)
						)
						(arc
							(start 0.2032 0.3048)
							(mid 0.275042 0.275042)
							(end 0.3048 0.2032)
						)
					)
					(width 0)
					(fill yes)
				)
			)
		)
	)
	(footprint ""
		(layer "F.Cu")
		(at 98.806 -225.806 90)
		(property "Reference" "R9465"
			(at 0 0 90)
			(layer "F.SilkS")
			(hide yes)
			(effects
				(font
					(size 1.27 1.27)
				)
			)
		)
		(property "Value" "4K7R2J-2-GP"
			(at 0.064008 -3.993896 90)
			(unlocked yes)
			(layer "F.Fab")
			(hide yes)
			(effects
				(font
					(size 1.016 1.016)
					(thickness 0.1524)
				)
			)
		)
		(property "Device Type" "R402H16"
			(at 0.064008 -5.517896 90)
			(unlocked yes)
			(layer "F.Fab")
			(hide yes)
			(effects
				(font
					(size 1.016 1.016)
					(thickness 0.1524)
				)
			)
		)
		(duplicate_pad_numbers_are_jumpers no)
		(fp_line
			(start 0.508 -0.9398)
			(end -0.508 -0.9398)
			(stroke
				(width 0.1524)
				(type default)
			)
			(layer "F.SilkS")
		)
		(fp_line
			(start -0.508 -0.9398)
			(end -0.508 0.9398)
			(stroke
				(width 0.1524)
				(type default)
			)
			(layer "F.SilkS")
		)
		(fp_rect
			(start -0.508 0.9398)
			(end 0.508 -0.9398)
			(stroke
				(width 0)
				(type default)
			)
			(fill no)
			(layer "F.CrtYd")
		)
		(fp_rect
			(start -0.508 0.9398)
			(end 0.508 -0.9398)
			(stroke
				(width 0)
				(type default)
			)
			(fill no)
			(layer "F.Fab")
		)
		(pad "1" smd custom
			(at 0 -0.4445 90)
			(size 0.1397 0.1397)
			(layers "F.Cu" "F.Mask" "F.Paste")
			(net "P3V3")
			(options
				(clearance outline)
				(anchor circle)
			)
			(primitives
				(gr_poly
					(pts
						(arc
							(start -0.1778 -0.2794)
							(mid -0.249642 -0.249642)
							(end -0.2794 -0.1778)
						)
						(arc
							(start -0.2794 0.1778)
							(mid -0.249642 0.249642)
							(end -0.1778 0.2794)
						)
						(arc
							(start 0.1778 0.2794)
							(mid 0.249642 0.249642)
							(end 0.2794 0.1778)
						)
						(arc
							(start 0.2794 -0.1778)
							(mid 0.249642 -0.249642)
							(end 0.1778 -0.2794)
						)
					)
					(width 0)
					(fill yes)
				)
			)
		)
		(pad "2" smd custom
			(at 0 0.4445 90)
			(size 0.1397 0.1397)
			(layers "F.Cu" "F.Mask" "F.Paste")
			(net "SSD_PRSNT_NET7")
			(options
				(clearance outline)
				(anchor circle)
			)
			(primitives
				(gr_poly
					(pts
						(arc
							(start -0.1778 -0.2794)
							(mid -0.249642 -0.249642)
							(end -0.2794 -0.1778)
						)
						(arc
							(start -0.2794 0.1778)
							(mid -0.249642 0.249642)
							(end -0.1778 0.2794)
						)
						(arc
							(start 0.1778 0.2794)
							(mid 0.249642 0.249642)
							(end 0.2794 0.1778)
						)
						(arc
							(start 0.2794 -0.1778)
							(mid 0.249642 -0.249642)
							(end 0.1778 -0.2794)
						)
					)
					(width 0)
					(fill yes)
				)
			)
		)
	)
	(footprint ""
		(layer "F.Cu")
		(at 37.7698 -315.8744)
		(property "Reference" "R577"
			(at 0 0 0)
			(layer "F.SilkS")
			(hide yes)
			(effects
				(font
					(size 1.27 1.27)
				)
			)
		)
		(property "Value" "300KR2F-GP"
			(at 0.064008 -3.993896 0)
			(unlocked yes)
			(layer "F.Fab")
			(hide yes)
			(effects
				(font
					(size 1.016 1.016)
					(thickness 0.1524)
				)
			)
		)
		(property "Device Type" "R402H16"
			(at 0.064008 -5.517896 0)
			(unlocked yes)
			(layer "F.Fab")
			(hide yes)
			(effects
				(font
					(size 1.016 1.016)
					(thickness 0.1524)
				)
			)
		)
		(duplicate_pad_numbers_are_jumpers no)
		(fp_line
			(start -0.508 -0.9398)
			(end -0.508 0.9398)
			(stroke
				(width 0.1524)
				(type default)
			)
			(layer "F.SilkS")
		)
		(fp_line
			(start 0.508 -0.9398)
			(end -0.508 -0.9398)
			(stroke
				(width 0.1524)
				(type default)
			)
			(layer "F.SilkS")
		)
		(fp_rect
			(start -0.508 0.9398)
			(end 0.508 -0.9398)
			(stroke
				(width 0)
				(type default)
			)
			(fill no)
			(layer "F.CrtYd")
		)
		(fp_rect
			(start -0.508 0.9398)
			(end 0.508 -0.9398)
			(stroke
				(width 0)
				(type default)
			)
			(fill no)
			(layer "F.Fab")
		)
		(pad "1" smd custom
			(at 0 -0.4445)
			(size 0.1397 0.1397)
			(layers "F.Cu" "F.Mask" "F.Paste")
			(net "SW_SSD11_N")
			(options
				(clearance outline)
				(anchor circle)
			)
			(primitives
				(gr_poly
					(pts
						(arc
							(start -0.1778 -0.2794)
							(mid -0.249642 -0.249642)
							(end -0.2794 -0.1778)
						)
						(arc
							(start -0.2794 0.1778)
							(mid -0.249642 0.249642)
							(end -0.1778 0.2794)
						)
						(arc
							(start 0.1778 0.2794)
							(mid 0.249642 0.249642)
							(end 0.2794 0.1778)
						)
						(arc
							(start 0.2794 -0.1778)
							(mid 0.249642 -0.249642)
							(end 0.1778 -0.2794)
						)
					)
					(width 0)
					(fill yes)
				)
			)
		)
		(pad "2" smd custom
			(at 0 0.4445)
			(size 0.1397 0.1397)
			(layers "F.Cu" "F.Mask" "F.Paste")
			(net "P12V")
			(options
				(clearance outline)
				(anchor circle)
			)
			(primitives
				(gr_poly
					(pts
						(arc
							(start -0.1778 -0.2794)
							(mid -0.249642 -0.249642)
							(end -0.2794 -0.1778)
						)
						(arc
							(start -0.2794 0.1778)
							(mid -0.249642 0.249642)
							(end -0.1778 0.2794)
						)
						(arc
							(start 0.1778 0.2794)
							(mid 0.249642 0.249642)
							(end 0.2794 0.1778)
						)
						(arc
							(start 0.2794 -0.1778)
							(mid 0.249642 -0.249642)
							(end 0.1778 -0.2794)
						)
					)
					(width 0)
					(fill yes)
				)
			)
		)
	)
	(footprint ""
		(layer "F.Cu")
		(at 41.184576 -145.67789 180)
		(property "Reference" "R9943"
			(at 0 0 180)
			(layer "F.SilkS")
			(hide yes)
			(effects
				(font
					(size 1.27 1.27)
				)
			)
		)
		(property "Value" "4K7R2J-2-GP"
			(at 0.064008 -3.993896 180)
			(unlocked yes)
			(layer "F.Fab")
			(hide yes)
			(effects
				(font
					(size 1.016 1.016)
					(thickness 0.1524)
				)
			)
		)
		(property "Device Type" "R402H16"
			(at 0.064008 -5.517896 180)
			(unlocked yes)
			(layer "F.Fab")
			(hide yes)
			(effects
				(font
					(size 1.016 1.016)
					(thickness 0.1524)
				)
			)
		)
		(duplicate_pad_numbers_are_jumpers no)
		(fp_line
			(start 0.508 -0.9398)
			(end -0.508 -0.9398)
			(stroke
				(width 0.1524)
				(type default)
			)
			(layer "F.SilkS")
		)
		(fp_line
			(start -0.508 -0.9398)
			(end -0.508 0.9398)
			(stroke
				(width 0.1524)
				(type default)
			)
			(layer "F.SilkS")
		)
		(fp_rect
			(start -0.508 0.9398)
			(end 0.508 -0.9398)
			(stroke
				(width 0)
				(type default)
			)
			(fill no)
			(layer "F.CrtYd")
		)
		(fp_rect
			(start -0.508 0.9398)
			(end 0.508 -0.9398)
			(stroke
				(width 0)
				(type default)
			)
			(fill no)
			(layer "F.Fab")
		)
		(pad "1" smd custom
			(at 0 -0.4445 180)
			(size 0.1397 0.1397)
			(layers "F.Cu" "F.Mask" "F.Paste")
			(net "P3V3")
			(options
				(clearance outline)
				(anchor circle)
			)
			(primitives
				(gr_poly
					(pts
						(arc
							(start -0.1778 -0.2794)
							(mid -0.249642 -0.249642)
							(end -0.2794 -0.1778)
						)
						(arc
							(start -0.2794 0.1778)
							(mid -0.249642 0.249642)
							(end -0.1778 0.2794)
						)
						(arc
							(start 0.1778 0.2794)
							(mid 0.249642 0.249642)
							(end 0.2794 0.1778)
						)
						(arc
							(start 0.2794 -0.1778)
							(mid 0.249642 -0.249642)
							(end 0.1778 -0.2794)
						)
					)
					(width 0)
					(fill yes)
				)
			)
		)
		(pad "2" smd custom
			(at 0 0.4445 180)
			(size 0.1397 0.1397)
			(layers "F.Cu" "F.Mask" "F.Paste")
			(net "ATTN_LED_DR8_MOS_N")
			(options
				(clearance outline)
				(anchor circle)
			)
			(primitives
				(gr_poly
					(pts
						(arc
							(start -0.1778 -0.2794)
							(mid -0.249642 -0.249642)
							(end -0.2794 -0.1778)
						)
						(arc
							(start -0.2794 0.1778)
							(mid -0.249642 0.249642)
							(end -0.1778 0.2794)
						)
						(arc
							(start 0.1778 0.2794)
							(mid 0.249642 0.249642)
							(end 0.2794 0.1778)
						)
						(arc
							(start 0.2794 -0.1778)
							(mid 0.249642 -0.249642)
							(end 0.1778 -0.2794)
						)
					)
					(width 0)
					(fill yes)
				)
			)
		)
	)
)
